# T6G (Grand Teton) — schematic netlist excerpt (pin names and nets, part order shuffled) for the footprints in the layout excerpt that follows; sources: Cadence DE-HDL packaged netlist, KiCad conversion of 04192023_DAF0TMB3IC0_F0TG_MB_C_brd_V02_OCP.brd

OSC1  Q_OSC4P  50MHZ OSC  pkg SMLF  page 133
  OE  = CLK_50M_EN
  GND  = GND
  \out\  = CLK_50M_RMII
  VDD  = P3V3_AUX

PC370  Q_CAP  2.2UF 10V 10% X6S  pkg C0402  page 218 : A = PVDDCR_CPU1_P1_VCC2 ; B = GND
R1055  Q_RES  1K 1% CHIP  pkg 0201LF  page 298 : A = P1V8_CPU0_RT_1D ; B = RT_CPU0_P2_ADDR3

(kicad_pcb
	(version 20260206)
	(generator "pcbnew")
	(generator_version "10.0")
	(general
		(thickness 1.6)
		(legacy_teardrops no)
	)
	(paper "A4")
	(title_block
		(title "04192023_DAF0TMB3IC0_F0TG_MB_C_brd_V02_OCP.brd")
		(comment 1 "Grand Teton / footprints 3467-3469 of 8354")
	)
	(layers
		(0 "F.Cu" signal "TOP")
		(4 "In1.Cu" signal "GND")
		(6 "In2.Cu" signal "IN1")
		(8 "In3.Cu" signal "GND1")
		(10 "In4.Cu" signal "IN2")
		(12 "In5.Cu" signal "GND2")
		(14 "In6.Cu" signal "IN3")
		(16 "In7.Cu" signal "GND3")
		(18 "In8.Cu" signal "VCC")
		(20 "In9.Cu" signal "VCC1")
		(22 "In10.Cu" signal "GND4")
		(24 "In11.Cu" signal "IN4")
		(26 "In12.Cu" signal "GND5")
		(28 "In13.Cu" signal "IN5")
		(30 "In14.Cu" signal "GND6")
		(32 "In15.Cu" signal "IN6")
		(34 "In16.Cu" signal "GND7")
		(2 "B.Cu" signal "BOTTOM")
		(9 "F.Adhes" user "F.Adhesive")
		(11 "B.Adhes" user "B.Adhesive")
		(13 "F.Paste" user "Package Geometry/Pastemask Top")
		(15 "B.Paste" user "Package Geometry/Pastemask Bottom")
		(5 "F.SilkS" user "Ref Des/Silkscreen Top")
		(7 "B.SilkS" user "Ref Des/Silkscreen Bottom")
		(1 "F.Mask" user "Board Geometry/Soldermask Top")
		(3 "B.Mask" user "Board Geometry/Soldermask Bottom")
		(17 "Dwgs.User" user "User.Drawings")
		(19 "Cmts.User" user "User.Comments")
		(21 "Eco1.User" user "User.Eco1")
		(23 "Eco2.User" user "User.Eco2")
		(25 "Edge.Cuts" user "Board Geometry/Outline")
		(27 "Margin" user)
		(31 "F.CrtYd" user "Package Geometry/Place Bound Top")
		(29 "B.CrtYd" user "Package Geometry/Place Bound Bottom")
		(35 "F.Fab" user "Ref Des/Assembly Top")
		(33 "B.Fab" user "Ref Des/Assembly Bottom")
	)
	(footprint ""
		(layer "F.Cu")
		(at 214.86241 -26.111454 90)
		(property "Reference" "OSC1"
			(at 2.590546 -0.070612 0)
			(unlocked yes)
			(layer "F.SilkS")
			(effects
				(font
					(size 0.7874 0.5842)
					(thickness 0.1524)
				)
				(justify left)
			)
		)
		(property "Value" ""
			(at 0 0 90)
			(layer "F.Fab")
			(effects
				(font
					(size 1.27 1.27)
				)
			)
		)
		(duplicate_pad_numbers_are_jumpers no)
		(fp_line
			(start 1.546098 -1.94945)
			(end -1.546098 -1.94945)
			(stroke
				(width 0.1524)
				(type default)
			)
			(layer "F.SilkS")
		)
		(fp_line
			(start -1.546098 -1.94945)
			(end -1.546098 1.94945)
			(stroke
				(width 0.1524)
				(type default)
			)
			(layer "F.SilkS")
		)
		(fp_line
			(start 1.546098 1.94945)
			(end 1.546098 -1.94945)
			(stroke
				(width 0.1524)
				(type default)
			)
			(layer "F.SilkS")
		)
		(fp_line
			(start -1.546098 1.94945)
			(end 1.546098 1.94945)
			(stroke
				(width 0.1524)
				(type default)
			)
			(layer "F.SilkS")
		)
		(fp_poly
			(pts
				(xy -1.085596 -2.087372) (xy -0.450596 -3.408172) (xy -1.568196 -3.408172)
			)
			(stroke
				(width 0)
				(type default)
			)
			(fill yes)
			(layer "F.SilkS")
		)
		(fp_line
			(start 1.299972 -1.649984)
			(end 1.299972 1.649984)
			(stroke
				(width 0.1)
				(type default)
			)
			(layer "F.Fab")
		)
		(fp_line
			(start -1.299972 -1.649984)
			(end 1.299972 -1.649984)
			(stroke
				(width 0.1)
				(type default)
			)
			(layer "F.Fab")
		)
		(fp_line
			(start 1.299972 1.649984)
			(end -1.299972 1.649984)
			(stroke
				(width 0.1)
				(type default)
			)
			(layer "F.Fab")
		)
		(fp_line
			(start -1.299972 1.649984)
			(end -1.299972 -1.649984)
			(stroke
				(width 0.1)
				(type default)
			)
			(layer "F.Fab")
		)
		(fp_poly
			(pts
				(xy -1.768094 -1.059942) (xy -3.088894 -1.694942) (xy -3.088894 -0.577342)
			)
			(stroke
				(width 0)
				(type default)
			)
			(fill yes)
			(layer "F.Fab")
		)
		(pad "1" smd rect
			(at -0.8001 -1.059942 90)
			(size 1.2192 1.4986)
			(layers "F.Cu" "F.Mask" "F.Paste")
			(net "CLK_50M_EN")
		)
		(pad "2" smd rect
			(at -0.8001 1.059942 270)
			(size 1.2192 1.4986)
			(layers "F.Cu" "F.Mask" "F.Paste")
			(net "GND")
		)
		(pad "3" smd rect
			(at 0.8001 1.059942 90)
			(size 1.2192 1.4986)
			(layers "F.Cu" "F.Mask" "F.Paste")
			(net "CLK_50M_RMII")
		)
		(pad "4" smd rect
			(at 0.8001 -1.059942 90)
			(size 1.2192 1.4986)
			(layers "F.Cu" "F.Mask" "F.Paste")
			(net "P3V3_AUX")
		)
	)
	(footprint ""
		(layer "F.Cu")
		(at 430.2379 -400.987768 -90)
		(property "Reference" "R1055"
			(at 0 0 270)
			(layer "F.SilkS")
			(hide yes)
			(effects
				(font
					(size 1.27 1.27)
				)
			)
		)
		(property "Value" ""
			(at 0 0 270)
			(layer "F.Fab")
			(effects
				(font
					(size 1.27 1.27)
				)
			)
		)
		(duplicate_pad_numbers_are_jumpers no)
		(fp_line
			(start -0.32512 0.175006)
			(end -0.32512 -0.175006)
			(stroke
				(width 0.1)
				(type default)
			)
			(layer "F.Fab")
		)
		(fp_line
			(start 0.32512 0.175006)
			(end -0.32512 0.175006)
			(stroke
				(width 0.1)
				(type default)
			)
			(layer "F.Fab")
		)
		(fp_line
			(start -0.32512 -0.175006)
			(end 0.32512 -0.175006)
			(stroke
				(width 0.1)
				(type default)
			)
			(layer "F.Fab")
		)
		(fp_line
			(start 0.32512 -0.175006)
			(end 0.32512 0.175006)
			(stroke
				(width 0.1)
				(type default)
			)
			(layer "F.Fab")
		)
		(pad "1" smd rect
			(at -0.2667 0 270)
			(size 0.3048 0.381)
			(layers "F.Cu" "F.Mask" "F.Paste")
			(net "P1V8_CPU0_RT_1D")
		)
		(pad "2" smd rect
			(at 0.2667 0 90)
			(size 0.3048 0.381)
			(layers "F.Cu" "F.Mask" "F.Paste")
			(net "RT_CPU0_P2_ADDR3")
		)
	)
	(footprint ""
		(layer "F.Cu")
		(at 75.081638 -337.658202 90)
		(property "Reference" "PC370"
			(at 0 0 90)
			(layer "F.SilkS")
			(hide yes)
			(effects
				(font
					(size 1.27 1.27)
				)
			)
		)
		(property "Value" ""
			(at 0 0 90)
			(layer "F.Fab")
			(effects
				(font
					(size 1.27 1.27)
				)
			)
		)
		(duplicate_pad_numbers_are_jumpers no)
		(fp_line
			(start 0.7874 -0.4064)
			(end 0.7874 0.4064)
			(stroke
				(width 0.1524)
				(type default)
			)
			(layer "F.SilkS")
		)
		(fp_line
			(start -0.7874 -0.4064)
			(end 0.7874 -0.4064)
			(stroke
				(width 0.1524)
				(type default)
			)
			(layer "F.SilkS")
		)
		(fp_line
			(start 0.7874 0.4064)
			(end 0.415798 0.4064)
			(stroke
				(width 0.1524)
				(type default)
			)
			(layer "F.SilkS")
		)
		(fp_line
			(start -0.447802 0.4064)
			(end -0.7874 0.4064)
			(stroke
				(width 0.1524)
				(type default)
			)
			(layer "F.SilkS")
		)
		(fp_line
			(start -0.7874 0.4064)
			(end -0.7874 -0.4064)
			(stroke
				(width 0.1524)
				(type default)
			)
			(layer "F.SilkS")
		)
		(fp_line
			(start -0.12065 -0.305054)
			(end -0.12065 -0.2794)
			(stroke
				(width 0.1)
				(type default)
			)
			(layer "F.Fab")
		)
		(fp_line
			(start -0.67945 -0.305054)
			(end -0.12065 -0.305054)
			(stroke
				(width 0.1)
				(type default)
			)
			(layer "F.Fab")
		)
		(fp_line
			(start 0.67945 -0.3048)
			(end 0.67945 0.3048)
			(stroke
				(width 0.1)
				(type default)
			)
			(layer "F.Fab")
		)
		(fp_line
			(start 0.12065 -0.3048)
			(end 0.67945 -0.3048)
			(stroke
				(width 0.1)
				(type default)
			)
			(layer "F.Fab")
		)
		(fp_line
			(start 0.12065 -0.2794)
			(end 0.12065 -0.3048)
			(stroke
				(width 0.1)
				(type default)
			)
			(layer "F.Fab")
		)
		(fp_line
			(start -0.12065 -0.2794)
			(end 0.12065 -0.2794)
			(stroke
				(width 0.1)
				(type default)
			)
			(layer "F.Fab")
		)
		(fp_line
			(start 0.120396 0.2794)
			(end -0.12065 0.2794)
			(stroke
				(width 0.1)
				(type default)
			)
			(layer "F.Fab")
		)
		(fp_line
			(start -0.12065 0.2794)
			(end -0.12065 0.3048)
			(stroke
				(width 0.1)
				(type default)
			)
			(layer "F.Fab")
		)
		(fp_line
			(start 0.67945 0.3048)
			(end 0.120396 0.3048)
			(stroke
				(width 0.1)
				(type default)
			)
			(layer "F.Fab")
		)
		(fp_line
			(start 0.120396 0.3048)
			(end 0.120396 0.2794)
			(stroke
				(width 0.1)
				(type default)
			)
			(layer "F.Fab")
		)
		(fp_line
			(start -0.12065 0.3048)
			(end -0.67945 0.3048)
			(stroke
				(width 0.1)
				(type default)
			)
			(layer "F.Fab")
		)
		(fp_line
			(start -0.67945 0.3048)
			(end -0.67945 -0.305054)
			(stroke
				(width 0.1)
				(type default)
			)
			(layer "F.Fab")
		)
		(pad "1" smd circle
			(at -0.40005 0 90)
			(size 0 0)
			(layers "F.Cu" "F.Mask" "F.Paste")
			(net "PVDDCR_CPU1_P1_VCC2")
		)
		(pad "2" smd circle
			(at 0.40005 0 90)
			(size 0 0)
			(layers "F.Cu" "F.Mask" "F.Paste")
			(net "GND")
		)
	)
)
